(kicad_pcb
	(version 20241229)
	(generator "pcbnew")
	(generator_version "9.0")
	(general
		(thickness 1.294)
		(legacy_teardrops no)
	)
	(paper "A3")
	(title_block
		(title "Kintex 410T devboard")
		(date "2024-04-03")
		(rev "1.1.2")
		(comment 9 "footprints 83-88 of 975")
	)
	(layers
		(0 "F.Cu" mixed)
		(4 "In1.Cu" power)
		(6 "In2.Cu" power)
		(8 "In3.Cu" mixed)
		(10 "In4.Cu" power)
		(12 "In5.Cu" mixed)
		(14 "In6.Cu" power)
		(16 "In7.Cu" mixed)
		(18 "In8.Cu" power)
		(2 "B.Cu" mixed)
		(9 "F.Adhes" user "F.Adhesive")
		(11 "B.Adhes" user "B.Adhesive")
		(13 "F.Paste" user)
		(15 "B.Paste" user)
		(5 "F.SilkS" user "F.Silkscreen")
		(7 "B.SilkS" user "B.Silkscreen")
		(1 "F.Mask" user)
		(3 "B.Mask" user)
		(17 "Dwgs.User" user "User.Drawings")
		(19 "Cmts.User" user "User.Comments")
		(21 "Eco1.User" user "User.Eco1")
		(23 "Eco2.User" user "User.Eco2")
		(25 "Edge.Cuts" user)
		(27 "Margin" user)
		(31 "F.CrtYd" user "F.Courtyard")
		(29 "B.CrtYd" user "B.Courtyard")
		(35 "F.Fab" user)
		(33 "B.Fab" user)
	)
	(footprint "antmicro-footprints:R_0402_1005Metric"
		(layer "F.Cu")
		(at 218.8 165.7)
		(descr "Resistor SMD 0402")
		(tags "resistor SMD 0402")
		(property "Reference" "R8"
			(at -2.25 0.4 0)
			(layer "F.SilkS")
			(effects
				(font
					(size 0.7 0.7)
					(thickness 0.15)
				)
				(justify left bottom)
			)
		)
		(property "Value" "R_10k_0402"
			(at 0 1.4 0)
			(layer "F.Fab")
			(effects
				(font
					(size 0.7 0.7)
					(thickness 0.15)
				)
				(justify left bottom)
			)
		)
		(property "Description" "SMD Chip Resistor, 10 kohm, ± 1%, 62.5 mW, 0402 [1005 Metric], Thick Film, General Purpose"
			(at 0 0 0)
			(layer "F.Fab")
			(hide yes)
			(effects
				(font
					(size 1.27 1.27)
					(thickness 0.15)
				)
			)
		)
		(property "Author" "Antmicro"
			(at 0 0 0)
			(layer "F.Fab")
			(hide yes)
			(effects
				(font
					(size 1 1)
					(thickness 0.15)
				)
			)
		)
		(property "License" "Apache-2.0"
			(at 0 0 0)
			(layer "F.Fab")
			(hide yes)
			(effects
				(font
					(size 1 1)
					(thickness 0.15)
				)
			)
		)
		(property "MPN" "CR0402-FX-1002GLF"
			(at 0 0 0)
			(layer "F.Fab")
			(hide yes)
			(effects
				(font
					(size 1 1)
					(thickness 0.15)
				)
			)
		)
		(property "Manufacturer" "Bourns"
			(at 0 0 0)
			(layer "F.Fab")
			(hide yes)
			(effects
				(font
					(size 1 1)
					(thickness 0.15)
				)
			)
		)
		(property "Tolerance" "1%"
			(at 0 0 0)
			(layer "F.Fab")
			(hide yes)
			(effects
				(font
					(size 1 1)
					(thickness 0.15)
				)
			)
		)
		(property "Val" "10k"
			(at 0 0 0)
			(layer "F.Fab")
			(hide yes)
			(effects
				(font
					(size 1 1)
					(thickness 0.15)
				)
			)
		)
		(sheetname "FPGA Config")
		(sheetfile "fpga-config.kicad_sch")
		(attr smd)
		(fp_rect
			(start -0.925 -0.47)
			(end 0.925 0.47)
			(stroke
				(width 0.05)
				(type default)
			)
			(fill no)
			(layer "F.CrtYd")
		)
		(fp_rect
			(start -0.5 -0.25)
			(end 0.5 0.25)
			(stroke
				(width 0.15)
				(type solid)
			)
			(fill no)
			(layer "F.Fab")
		)
		(pad "1" smd roundrect
			(at -0.48 0)
			(size 0.59 0.64)
			(layers "F.Cu" "F.Mask" "F.Paste")
			(roundrect_rratio 0.25)
			(net 345 "Net-(U3-STBY)")
			(pintype "passive")
		)
		(pad "2" smd roundrect
			(at 0.48 0)
			(size 0.59 0.64)
			(layers "F.Cu" "F.Mask" "F.Paste")
			(roundrect_rratio 0.25)
			(net 24 "+3V3")
			(pintype "passive")
		)
	)
	(footprint "antmicro-footprints:R_Array_4x0201_Panasonic_EXB18V"
		(layer "F.Cu")
		(at 251.9 144.302)
		(property "Reference" "R281"
			(at -17.35 -39.002 0)
			(layer "F.SilkS")
			(effects
				(font
					(size 0.7 0.7)
					(thickness 0.15)
				)
				(justify right bottom)
			)
		)
		(property "Value" "R_4x33R_0201_array"
			(at -1.1 1.8 0)
			(layer "F.Fab")
			(effects
				(font
					(size 0.7 0.7)
					(thickness 0.15)
				)
				(justify left bottom)
			)
		)
		(property "Description" "Fixed Network Resistor, 33 ohm, Isolated, 4 Resistors, 0502 [1406 Metric], Flat, ± 5%"
			(at 0 0 0)
			(layer "F.Fab")
			(hide yes)
			(effects
				(font
					(size 1.27 1.27)
					(thickness 0.15)
				)
			)
		)
		(property "Author" "Antmicro"
			(at 0 0 0)
			(layer "F.Fab")
			(hide yes)
			(effects
				(font
					(size 1 1)
					(thickness 0.15)
				)
			)
		)
		(property "License" "Apache-2.0"
			(at 0 0 0)
			(layer "F.Fab")
			(hide yes)
			(effects
				(font
					(size 1 1)
					(thickness 0.15)
				)
			)
		)
		(property "MPN" "EXB-18V330JX"
			(at 0 0 0)
			(layer "F.Fab")
			(hide yes)
			(effects
				(font
					(size 1 1)
					(thickness 0.15)
				)
			)
		)
		(property "Manufacturer" "Panasonic"
			(at 0 0 0)
			(layer "F.Fab")
			(hide yes)
			(effects
				(font
					(size 1 1)
					(thickness 0.15)
				)
			)
		)
		(property "Val" "R_4x33R_0201"
			(at 0 0 0)
			(layer "F.Fab")
			(hide yes)
			(effects
				(font
					(size 1 1)
					(thickness 0.15)
				)
			)
		)
		(sheetname "Supervisior MCU")
		(sheetfile "supervisor-mcu.kicad_sch")
		(attr smd)
		(fp_line
			(start -0.8 -0.45)
			(end -0.8 0.45)
			(stroke
				(width 0.12)
				(type solid)
			)
			(layer "F.SilkS")
		)
		(fp_line
			(start 0.8 -0.45)
			(end 0.8 0.45)
			(stroke
				(width 0.12)
				(type solid)
			)
			(layer "F.SilkS")
		)
		(fp_rect
			(start -0.898 -0.66)
			(end 0.898 0.65)
			(stroke
				(width 0.05)
				(type solid)
			)
			(fill no)
			(layer "F.CrtYd")
		)
		(pad "1" smd roundrect
			(at -0.6 0.298)
			(size 0.2 0.4)
			(layers "F.Cu" "F.Mask" "F.Paste")
			(roundrect_rratio 0.25)
			(net 1085 "/Supervisior MCU/PGOOD_VCCINT")
			(pinfunction "R1.1")
			(pintype "passive")
		)
		(pad "2" smd roundrect
			(at -0.202 0.298)
			(size 0.2 0.4)
			(layers "F.Cu" "F.Mask" "F.Paste")
			(roundrect_rratio 0.25)
			(net 1107 "/Supervisior MCU/USB_C_PD_RST")
			(pinfunction "R2.1")
			(pintype "passive")
		)
		(pad "3" smd roundrect
			(at 0.2 0.298)
			(size 0.2 0.4)
			(layers "F.Cu" "F.Mask" "F.Paste")
			(roundrect_rratio 0.25)
			(net 955 "/Supervisior MCU/FPGA_COPI")
			(pinfunction "R3.1")
			(pintype "passive")
		)
		(pad "4" smd roundrect
			(at 0.598 0.298)
			(size 0.2 0.4)
			(layers "F.Cu" "F.Mask" "F.Paste")
			(roundrect_rratio 0.25)
			(net 1100 "/Supervisior MCU/USB_WR")
			(pinfunction "R4.1")
			(pintype "passive")
		)
		(pad "5" smd roundrect
			(at 0.598 -0.3)
			(size 0.2 0.4)
			(layers "F.Cu" "F.Mask" "F.Paste")
			(roundrect_rratio 0.25)
			(net 1388 "/SUP_MCU.WR")
			(pinfunction "R4.2")
			(pintype "passive")
		)
		(pad "6" smd roundrect
			(at 0.2 -0.3)
			(size 0.2 0.4)
			(layers "F.Cu" "F.Mask" "F.Paste")
			(roundrect_rratio 0.25)
			(net 1327 "/SUP_MCU.FPGA_MOSI")
			(pinfunction "R3.2")
			(pintype "passive")
		)
		(pad "7" smd roundrect
			(at -0.202 -0.3)
			(size 0.2 0.4)
			(layers "F.Cu" "F.Mask" "F.Paste")
			(roundrect_rratio 0.25)
			(net 1349 "/SUP_MCU.PD_RST")
			(pinfunction "R2.2")
			(pintype "passive")
		)
		(pad "8" smd roundrect
			(at -0.6 -0.3)
			(size 0.2 0.4)
			(layers "F.Cu" "F.Mask" "F.Paste")
			(roundrect_rratio 0.25)
			(net 1389 "/SUP_MCU.PG_VCCINT")
			(pinfunction "R1.2")
			(pintype "passive")
		)
	)
	(footprint "antmicro-footprints:C_0402_1005Metric"
		(layer "F.Cu")
		(at 240.3 133.3 180)
		(descr "Capacitor SMD 0402")
		(tags "capacitor SMD 0402")
		(property "Reference" "C248"
			(at -3.3 3.125 180)
			(layer "F.SilkS")
			(effects
				(font
					(size 0.7 0.7)
					(thickness 0.15)
				)
				(justify left bottom)
			)
		)
		(property "Value" "C_100n_0402"
			(at 0 1.169 180)
			(layer "F.Fab")
			(effects
				(font
					(size 0.7 0.7)
					(thickness 0.15)
				)
				(justify left bottom)
			)
		)
		(property "Description" "SMD Multilayer Ceramic Capacitor, 0.1 µF, 50 V, 0402 [1005 Metric], ± 10%, X5R, GRM Series"
			(at 0 0 180)
			(layer "F.Fab")
			(hide yes)
			(effects
				(font
					(size 1.27 1.27)
					(thickness 0.15)
				)
			)
		)
		(property "Author" "Antmicro"
			(at 480.6 266.6 0)
			(layer "F.Fab")
			(hide yes)
			(effects
				(font
					(size 1 1)
					(thickness 0.15)
				)
			)
		)
		(property "Dielectric" "X5R"
			(at 480.6 266.6 0)
			(layer "F.Fab")
			(hide yes)
			(effects
				(font
					(size 1 1)
					(thickness 0.15)
				)
			)
		)
		(property "License" "Apache-2.0"
			(at 480.6 266.6 0)
			(layer "F.Fab")
			(hide yes)
			(effects
				(font
					(size 1 1)
					(thickness 0.15)
				)
			)
		)
		(property "MPN" "GRM155R61H104KE14D"
			(at 480.6 266.6 0)
			(layer "F.Fab")
			(hide yes)
			(effects
				(font
					(size 1 1)
					(thickness 0.15)
				)
			)
		)
		(property "Manufacturer" "Murata"
			(at 480.6 266.6 0)
			(layer "F.Fab")
			(hide yes)
			(effects
				(font
					(size 1 1)
					(thickness 0.15)
				)
			)
		)
		(property "Val" "100n"
			(at 480.6 266.6 0)
			(layer "F.Fab")
			(hide yes)
			(effects
				(font
					(size 1 1)
					(thickness 0.15)
				)
			)
		)
		(property "Voltage" "50V"
			(at 480.6 266.6 0)
			(layer "F.Fab")
			(hide yes)
			(effects
				(font
					(size 1 1)
					(thickness 0.15)
				)
			)
		)
		(sheetname "USB PHY")
		(sheetfile "usb-phy.kicad_sch")
		(attr smd)
		(fp_rect
			(start -0.925 -0.47)
			(end 0.925 0.47)
			(stroke
				(width 0.05)
				(type default)
			)
			(fill no)
			(layer "F.CrtYd")
		)
		(fp_line
			(start 0.504 0.248)
			(end -0.494 0.248)
			(stroke
				(width 0.15)
				(type solid)
			)
			(layer "F.Fab")
		)
		(fp_line
			(start 0.504 -0.25)
			(end 0.504 0.248)
			(stroke
				(width 0.15)
				(type solid)
			)
			(layer "F.Fab")
		)
		(fp_line
			(start -0.494 0.248)
			(end -0.494 -0.25)
			(stroke
				(width 0.15)
				(type solid)
			)
			(layer "F.Fab")
		)
		(fp_line
			(start -0.494 -0.25)
			(end 0.504 -0.25)
			(stroke
				(width 0.15)
				(type solid)
			)
			(layer "F.Fab")
		)
		(pad "1" smd roundrect
			(at -0.48 0 180)
			(size 0.59 0.64)
			(layers "F.Cu" "F.Mask" "F.Paste")
			(roundrect_rratio 0.25)
			(net 1 "GND")
			(pintype "passive")
		)
		(pad "2" smd roundrect
			(at 0.48 0 180)
			(size 0.59 0.64)
			(layers "F.Cu" "F.Mask" "F.Paste")
			(roundrect_rratio 0.25)
			(net 707 "/USB PHY/FTDI_3V3")
			(pintype "passive")
		)
	)
	(footprint "antmicro-footprints:C_0603_1608Metric"
		(layer "F.Cu")
		(at 181.25 172.7 -90)
		(descr "Capacitor SMD 0603")
		(tags "capacitor 0603")
		(property "Reference" "C332"
			(at 1 -0.125 90)
			(unlocked yes)
			(layer "F.SilkS")
			(effects
				(font
					(size 0.7 0.7)
					(thickness 0.15)
				)
				(justify right bottom)
			)
		)
		(property "Value" "C_22u_0603"
			(at 0 1.6 90)
			(layer "F.Fab")
			(effects
				(font
					(size 0.7 0.7)
					(thickness 0.15)
				)
				(justify right bottom)
			)
		)
		(property "Description" "SMD Multilayer Ceramic Capacitor, 22 µF, 6.3 V, 0603 [1608 Metric], ± 20%, X5R, GRM Series"
			(at 0 0 270)
			(layer "F.Fab")
			(hide yes)
			(effects
				(font
					(size 1.27 1.27)
					(thickness 0.15)
				)
			)
		)
		(property "Author" "Antmicro"
			(at 8.55 353.95 0)
			(layer "F.Fab")
			(hide yes)
			(effects
				(font
					(size 1 1)
					(thickness 0.15)
				)
			)
		)
		(property "Dielectric" ""
			(at 8.55 353.95 0)
			(layer "F.Fab")
			(hide yes)
			(effects
				(font
					(size 1 1)
					(thickness 0.15)
				)
			)
		)
		(property "License" "Apache-2.0"
			(at 8.55 353.95 0)
			(layer "F.Fab")
			(hide yes)
			(effects
				(font
					(size 1 1)
					(thickness 0.15)
				)
			)
		)
		(property "MPN" "GRM188R60J226MEA0D"
			(at 8.55 353.95 0)
			(layer "F.Fab")
			(hide yes)
			(effects
				(font
					(size 1 1)
					(thickness 0.15)
				)
			)
		)
		(property "Manufacturer" "Murata"
			(at 8.55 353.95 0)
			(layer "F.Fab")
			(hide yes)
			(effects
				(font
					(size 1 1)
					(thickness 0.15)
				)
			)
		)
		(property "Val" "22u"
			(at 8.55 353.95 0)
			(layer "F.Fab")
			(hide yes)
			(effects
				(font
					(size 1 1)
					(thickness 0.15)
				)
			)
		)
		(property "Voltage" ""
			(at 8.55 353.95 0)
			(layer "F.Fab")
			(hide yes)
			(effects
				(font
					(size 1 1)
					(thickness 0.15)
				)
			)
		)
		(sheetname "DC-DC Converters")
		(sheetfile "dc-dc.kicad_sch")
		(attr smd)
		(fp_line
			(start -0.15 0.4)
			(end 0.15 0.4)
			(stroke
				(width 0.15)
				(type solid)
			)
			(layer "F.SilkS")
		)
		(fp_line
			(start -0.15 -0.4)
			(end 0.15 -0.4)
			(stroke
				(width 0.15)
				(type solid)
			)
			(layer "F.SilkS")
		)
		(fp_rect
			(start -1.25 -0.65)
			(end 1.25 0.65)
			(stroke
				(width 0.05)
				(type solid)
			)
			(fill no)
			(layer "F.CrtYd")
		)
		(fp_rect
			(start -0.8 -0.4)
			(end 0.8 0.4)
			(stroke
				(width 0.15)
				(type solid)
			)
			(fill no)
			(layer "F.Fab")
		)
		(pad "1" smd roundrect
			(at -0.7 0 270)
			(size 0.8 1)
			(layers "F.Cu" "F.Mask" "F.Paste")
			(roundrect_rratio 0.2)
			(net 1 "GND")
			(pintype "passive")
		)
		(pad "2" smd roundrect
			(at 0.7 0 270)
			(size 0.8 1)
			(layers "F.Cu" "F.Mask" "F.Paste")
			(roundrect_rratio 0.2)
			(net 739 "/DC-DC Converters/5V_local")
			(pintype "passive")
		)
	)
	(footprint "antmicro-footprints:C_0402_1005Metric"
		(layer "F.Cu")
		(at 222.4 155.1 90)
		(descr "Capacitor SMD 0402")
		(tags "capacitor SMD 0402")
		(property "Reference" "C274"
			(at -1.55 1.25 90)
			(layer "F.SilkS")
			(effects
				(font
					(size 0.7 0.7)
					(thickness 0.15)
				)
				(justify left bottom)
			)
		)
		(property "Value" "C_10u_0402"
			(at 0 1.4 90)
			(layer "F.Fab")
			(effects
				(font
					(size 0.7 0.7)
					(thickness 0.15)
				)
				(justify left bottom)
			)
		)
		(property "Description" "SMD Multilayer Ceramic Capacitor, 10 µF, 6.3 V, 0402 [1005 Metric], ± 20%, X5R, CC Series"
			(at 0 0 90)
			(layer "F.Fab")
			(hide yes)
			(effects
				(font
					(size 1.27 1.27)
					(thickness 0.15)
				)
			)
		)
		(property "Author" "Antmicro"
			(at 377.5 -67.3 0)
			(layer "F.Fab")
			(hide yes)
			(effects
				(font
					(size 1 1)
					(thickness 0.15)
				)
			)
		)
		(property "Dielectric" ""
			(at 377.5 -67.3 0)
			(layer "F.Fab")
			(hide yes)
			(effects
				(font
					(size 1 1)
					(thickness 0.15)
				)
			)
		)
		(property "License" "Apache-2.0"
			(at 377.5 -67.3 0)
			(layer "F.Fab")
			(hide yes)
			(effects
				(font
					(size 1 1)
					(thickness 0.15)
				)
			)
		)
		(property "MPN" "CC0402MRX5R5BB106"
			(at 377.5 -67.3 0)
			(layer "F.Fab")
			(hide yes)
			(effects
				(font
					(size 1 1)
					(thickness 0.15)
				)
			)
		)
		(property "Manufacturer" "YAGEO"
			(at 377.5 -67.3 0)
			(layer "F.Fab")
			(hide yes)
			(effects
				(font
					(size 1 1)
					(thickness 0.15)
				)
			)
		)
		(property "Val" "10u"
			(at 377.5 -67.3 0)
			(layer "F.Fab")
			(hide yes)
			(effects
				(font
					(size 1 1)
					(thickness 0.15)
				)
			)
		)
		(property "Voltage" ""
			(at 377.5 -67.3 0)
			(layer "F.Fab")
			(hide yes)
			(effects
				(font
					(size 1 1)
					(thickness 0.15)
				)
			)
		)
		(sheetname "HDMI + Ethernet")
		(sheetfile "hdmi-ethernet.kicad_sch")
		(attr smd)
		(fp_rect
			(start -0.925 -0.47)
			(end 0.925 0.47)
			(stroke
				(width 0.05)
				(type default)
			)
			(fill no)
			(layer "F.CrtYd")
		)
		(fp_line
			(start 0.504 -0.25)
			(end 0.504 0.248)
			(stroke
				(width 0.15)
				(type solid)
			)
			(layer "F.Fab")
		)
		(fp_line
			(start -0.494 -0.25)
			(end 0.504 -0.25)
			(stroke
				(width 0.15)
				(type solid)
			)
			(layer "F.Fab")
		)
		(fp_line
			(start 0.504 0.248)
			(end -0.494 0.248)
			(stroke
				(width 0.15)
				(type solid)
			)
			(layer "F.Fab")
		)
		(fp_line
			(start -0.494 0.248)
			(end -0.494 -0.25)
			(stroke
				(width 0.15)
				(type solid)
			)
			(layer "F.Fab")
		)
		(pad "1" smd roundrect
			(at -0.48 0 90)
			(size 0.59 0.64)
			(layers "F.Cu" "F.Mask" "F.Paste")
			(roundrect_rratio 0.25)
			(net 1 "GND")
			(pintype "passive")
		)
		(pad "2" smd roundrect
			(at 0.48 0 90)
			(size 0.59 0.64)
			(layers "F.Cu" "F.Mask" "F.Paste")
			(roundrect_rratio 0.25)
			(net 721 "/HDMI + Ethernet/ETH_3V3")
			(pintype "passive")
		)
	)
	(footprint "antmicro-footprints:FB_0603_1608Metric"
		(layer "F.Cu")
		(at 201.85 103.868 90)
		(property "Reference" "FB10"
			(at -9.132 5.15 90)
			(layer "F.SilkS")
			(effects
				(font
					(size 0.7 0.7)
					(thickness 0.15)
				)
				(justify left bottom)
			)
		)
		(property "Value" "FB_120Z_2A_Murata-BLM18PG_0603"
			(at 0 1.7 90)
			(layer "F.Fab")
			(effects
				(font
					(size 0.7 0.7)
					(thickness 0.15)
				)
				(justify left bottom)
			)
		)
		(property "Description" "Ferrite Bead, 0603 [1608 Metric], 120 ohm, 2 A, BLM18P, 0.05 ohm, ± 25%, DC power line"
			(at 0 0 90)
			(layer "F.Fab")
			(hide yes)
			(effects
				(font
					(size 1.27 1.27)
					(thickness 0.15)
				)
			)
		)
		(property "Author" "Antmicro"
			(at 305.718 -97.982 0)
			(layer "F.Fab")
			(hide yes)
			(effects
				(font
					(size 1 1)
					(thickness 0.15)
				)
			)
		)
		(property "Current" ""
			(at 305.718 -97.982 0)
			(layer "F.Fab")
			(hide yes)
			(effects
				(font
					(size 1 1)
					(thickness 0.15)
				)
			)
		)
		(property "License" "Apache-2.0"
			(at 305.718 -97.982 0)
			(layer "F.Fab")
			(hide yes)
			(effects
				(font
					(size 1 1)
					(thickness 0.15)
				)
			)
		)
		(property "MPN" "BLM18PG121SN1D"
			(at 305.718 -97.982 0)
			(layer "F.Fab")
			(hide yes)
			(effects
				(font
					(size 1 1)
					(thickness 0.15)
				)
			)
		)
		(property "Manufacturer" "Murata"
			(at 305.718 -97.982 0)
			(layer "F.Fab")
			(hide yes)
			(effects
				(font
					(size 1 1)
					(thickness 0.15)
				)
			)
		)
		(property "Val" "120Z/2A"
			(at 305.718 -97.982 0)
			(layer "F.Fab")
			(hide yes)
			(effects
				(font
					(size 1 1)
					(thickness 0.15)
				)
			)
		)
		(sheetname "HDMI + Ethernet")
		(sheetfile "hdmi-ethernet.kicad_sch")
		(attr smd)
		(fp_line
			(start -0.15 -0.4)
			(end 0.15 -0.4)
			(stroke
				(width 0.15)
				(type solid)
			)
			(layer "F.SilkS")
		)
		(fp_line
			(start -0.15 0.4)
			(end 0.15 0.4)
			(stroke
				(width 0.15)
				(type solid)
			)
			(layer "F.SilkS")
		)
		(fp_rect
			(start -1.25 -0.65)
			(end 1.25 0.65)
			(stroke
				(width 0.05)
				(type solid)
			)
			(fill no)
			(layer "F.CrtYd")
		)
		(fp_line
			(start 0.8 -0.408)
			(end -0.803 -0.408)
			(stroke
				(width 0.15)
				(type solid)
			)
			(layer "F.Fab")
		)
		(fp_line
			(start 0.8 -0.408)
			(end 0.8 0.406)
			(stroke
				(width 0.15)
				(type solid)
			)
			(layer "F.Fab")
		)
		(fp_line
			(start 0.8 0.406)
			(end -0.803 0.406)
			(stroke
				(width 0.15)
				(type solid)
			)
			(layer "F.Fab")
		)
		(fp_line
			(start -0.803 0.406)
			(end -0.803 -0.408)
			(stroke
				(width 0.15)
				(type solid)
			)
			(layer "F.Fab")
		)
		(pad "1" smd roundrect
			(at -0.7 0 90)
			(size 0.8 1)
			(layers "F.Cu" "F.Mask" "F.Paste")
			(roundrect_rratio 0.2)
			(net 727 "+1V2")
			(pintype "passive")
		)
		(pad "2" smd roundrect
			(at 0.7 0 90)
			(size 0.8 1)
			(layers "F.Cu" "F.Mask" "F.Paste")
			(roundrect_rratio 0.2)
			(net 728 "/HDMI + Ethernet/GBE_AVDDL{slash}PLL")
			(pintype "passive")
		)
	)
)
